# S9S_MB_2U (Grand Teton) — schematic netlist excerpt (pin names and nets, part order shuffled) for the footprints in the layout excerpt that follows; sources: Cadence DE-HDL packaged netlist, KiCad conversion of 03242023_DA0F0TMBIJ0_F0T_Motherboard_J_brd_V01_OCP.brd

C479  Q_CAP  47UF 4V 20% X6S  pkg C0805  page 79 : A = PVCCFA_EHV_FIVRA_CPU1 ; B = GND
R3884  Q_RES  49.9 1% CHIP  pkg 0402LF  page 91 : A = I3C_SPD_DDREFGH_CPU0_LVC1_SCL_1 ; B = I3C_SPD_DDREFGH_CPU0_LVC1_SCL
C2355  Q_CAP  1UF 25V 10% X6S  pkg C0402  page 167 : A = P3V3_AUX ; B = GND

(kicad_pcb
	(version 20260206)
	(generator "pcbnew")
	(generator_version "10.0")
	(general
		(thickness 1.6)
		(legacy_teardrops no)
	)
	(paper "A4")
	(title_block
		(title "03242023_DA0F0TMBIJ0_F0T_Motherboard_J_brd_V01_OCP.brd")
		(comment 1 "Grand Teton / footprints 5208-5210 of 6105")
	)
	(layers
		(0 "F.Cu" signal "TOP")
		(4 "In1.Cu" signal "GND")
		(6 "In2.Cu" signal "IN1")
		(8 "In3.Cu" signal "GND1")
		(10 "In4.Cu" signal "IN2")
		(12 "In5.Cu" signal "GND2")
		(14 "In6.Cu" signal "IN3")
		(16 "In7.Cu" signal "GND3")
		(18 "In8.Cu" signal "VCC")
		(20 "In9.Cu" signal "VCC1")
		(22 "In10.Cu" signal "GND4")
		(24 "In11.Cu" signal "IN4")
		(26 "In12.Cu" signal "GND5")
		(28 "In13.Cu" signal "IN5")
		(30 "In14.Cu" signal "GND6")
		(32 "In15.Cu" signal "IN6")
		(34 "In16.Cu" signal "GND7")
		(2 "B.Cu" signal "BOTTOM")
		(9 "F.Adhes" user "F.Adhesive")
		(11 "B.Adhes" user "B.Adhesive")
		(13 "F.Paste" user "Package Geometry/Pastemask Top")
		(15 "B.Paste" user "Package Geometry/Pastemask Bottom")
		(5 "F.SilkS" user "Ref Des/Silkscreen Top")
		(7 "B.SilkS" user "Ref Des/Silkscreen Bottom")
		(1 "F.Mask" user "Board Geometry/Soldermask Top")
		(3 "B.Mask" user "Board Geometry/Soldermask Bottom")
		(17 "Dwgs.User" user "User.Drawings")
		(19 "Cmts.User" user "User.Comments")
		(21 "Eco1.User" user "User.Eco1")
		(23 "Eco2.User" user "User.Eco2")
		(25 "Edge.Cuts" user "Board Geometry/Outline")
		(27 "Margin" user)
		(31 "F.CrtYd" user "Package Geometry/Place Bound Top")
		(29 "B.CrtYd" user "Package Geometry/Place Bound Bottom")
		(35 "F.Fab" user "Ref Des/Assembly Top")
		(33 "B.Fab" user "Ref Des/Assembly Bottom")
	)
	(footprint ""
		(layer "B.Cu")
		(at 407.0731 -317.25108 90)
		(property "Reference" "R3884"
			(at 0 0 90)
			(layer "B.SilkS")
			(hide yes)
			(effects
				(font
					(size 1.27 1.27)
				)
				(justify mirror)
			)
		)
		(property "Value" ""
			(at 0 0 90)
			(layer "B.Fab")
			(effects
				(font
					(size 1.27 1.27)
				)
				(justify mirror)
			)
		)
		(duplicate_pad_numbers_are_jumpers no)
		(fp_line
			(start 0.7874 -0.4064)
			(end -0.7874 -0.4064)
			(stroke
				(width 0.1524)
				(type default)
			)
			(layer "B.SilkS")
		)
		(fp_line
			(start -0.7874 -0.4064)
			(end -0.7874 0.4064)
			(stroke
				(width 0.1524)
				(type default)
			)
			(layer "B.SilkS")
		)
		(fp_line
			(start 0.7874 0.4064)
			(end 0.7874 -0.4064)
			(stroke
				(width 0.1524)
				(type default)
			)
			(layer "B.SilkS")
		)
		(fp_line
			(start -0.7874 0.4064)
			(end 0.7874 0.4064)
			(stroke
				(width 0.1524)
				(type default)
			)
			(layer "B.SilkS")
		)
		(fp_line
			(start 0.67945 -0.305054)
			(end 0.12065 -0.305054)
			(stroke
				(width 0.1)
				(type default)
			)
			(layer "B.Fab")
		)
		(fp_line
			(start 0.12065 -0.305054)
			(end 0.12065 -0.2794)
			(stroke
				(width 0.1)
				(type default)
			)
			(layer "B.Fab")
		)
		(fp_line
			(start -0.12065 -0.3048)
			(end -0.67945 -0.3048)
			(stroke
				(width 0.1)
				(type default)
			)
			(layer "B.Fab")
		)
		(fp_line
			(start -0.67945 -0.3048)
			(end -0.67945 0.3048)
			(stroke
				(width 0.1)
				(type default)
			)
			(layer "B.Fab")
		)
		(fp_line
			(start 0.12065 -0.2794)
			(end -0.12065 -0.2794)
			(stroke
				(width 0.1)
				(type default)
			)
			(layer "B.Fab")
		)
		(fp_line
			(start -0.12065 -0.2794)
			(end -0.12065 -0.3048)
			(stroke
				(width 0.1)
				(type default)
			)
			(layer "B.Fab")
		)
		(fp_line
			(start 0.12065 0.2794)
			(end 0.12065 0.3048)
			(stroke
				(width 0.1)
				(type default)
			)
			(layer "B.Fab")
		)
		(fp_line
			(start -0.120396 0.2794)
			(end 0.12065 0.2794)
			(stroke
				(width 0.1)
				(type default)
			)
			(layer "B.Fab")
		)
		(fp_line
			(start 0.67945 0.3048)
			(end 0.67945 -0.305054)
			(stroke
				(width 0.1)
				(type default)
			)
			(layer "B.Fab")
		)
		(fp_line
			(start 0.12065 0.3048)
			(end 0.67945 0.3048)
			(stroke
				(width 0.1)
				(type default)
			)
			(layer "B.Fab")
		)
		(fp_line
			(start -0.120396 0.3048)
			(end -0.120396 0.2794)
			(stroke
				(width 0.1)
				(type default)
			)
			(layer "B.Fab")
		)
		(fp_line
			(start -0.67945 0.3048)
			(end -0.120396 0.3048)
			(stroke
				(width 0.1)
				(type default)
			)
			(layer "B.Fab")
		)
		(pad "1" smd circle
			(at 0.40005 0 270)
			(size 0 0)
			(layers "B.Cu" "B.Mask" "B.Paste")
			(net "I3C_SPD_DDREFGH_CPU0_LVC1_SCL_1")
		)
		(pad "2" smd circle
			(at -0.40005 0 270)
			(size 0 0)
			(layers "B.Cu" "B.Mask" "B.Paste")
			(net "I3C_SPD_DDREFGH_CPU0_LVC1_SCL")
		)
	)
	(footprint ""
		(layer "B.Cu")
		(at 35.586416 -395.243558 -90)
		(property "Reference" "C2355"
			(at 0 0 90)
			(layer "B.SilkS")
			(hide yes)
			(effects
				(font
					(size 1.27 1.27)
				)
				(justify mirror)
			)
		)
		(property "Value" ""
			(at 0 0 90)
			(layer "B.Fab")
			(effects
				(font
					(size 1.27 1.27)
				)
				(justify mirror)
			)
		)
		(duplicate_pad_numbers_are_jumpers no)
		(fp_line
			(start -0.7874 0.4064)
			(end 0.7874 0.4064)
			(stroke
				(width 0.1524)
				(type default)
			)
			(layer "B.SilkS")
		)
		(fp_line
			(start 0.7874 0.4064)
			(end 0.7874 -0.4064)
			(stroke
				(width 0.1524)
				(type default)
			)
			(layer "B.SilkS")
		)
		(fp_line
			(start -0.7874 -0.4064)
			(end -0.7874 0.4064)
			(stroke
				(width 0.1524)
				(type default)
			)
			(layer "B.SilkS")
		)
		(fp_line
			(start 0.7874 -0.4064)
			(end -0.7874 -0.4064)
			(stroke
				(width 0.1524)
				(type default)
			)
			(layer "B.SilkS")
		)
		(fp_line
			(start -0.67945 0.3048)
			(end -0.120396 0.3048)
			(stroke
				(width 0.1)
				(type default)
			)
			(layer "B.Fab")
		)
		(fp_line
			(start -0.120396 0.3048)
			(end -0.120396 0.2794)
			(stroke
				(width 0.1)
				(type default)
			)
			(layer "B.Fab")
		)
		(fp_line
			(start 0.12065 0.3048)
			(end 0.67945 0.3048)
			(stroke
				(width 0.1)
				(type default)
			)
			(layer "B.Fab")
		)
		(fp_line
			(start 0.67945 0.3048)
			(end 0.67945 -0.305054)
			(stroke
				(width 0.1)
				(type default)
			)
			(layer "B.Fab")
		)
		(fp_line
			(start -0.120396 0.2794)
			(end 0.12065 0.2794)
			(stroke
				(width 0.1)
				(type default)
			)
			(layer "B.Fab")
		)
		(fp_line
			(start 0.12065 0.2794)
			(end 0.12065 0.3048)
			(stroke
				(width 0.1)
				(type default)
			)
			(layer "B.Fab")
		)
		(fp_line
			(start -0.12065 -0.2794)
			(end -0.12065 -0.3048)
			(stroke
				(width 0.1)
				(type default)
			)
			(layer "B.Fab")
		)
		(fp_line
			(start 0.12065 -0.2794)
			(end -0.12065 -0.2794)
			(stroke
				(width 0.1)
				(type default)
			)
			(layer "B.Fab")
		)
		(fp_line
			(start -0.67945 -0.3048)
			(end -0.67945 0.3048)
			(stroke
				(width 0.1)
				(type default)
			)
			(layer "B.Fab")
		)
		(fp_line
			(start -0.12065 -0.3048)
			(end -0.67945 -0.3048)
			(stroke
				(width 0.1)
				(type default)
			)
			(layer "B.Fab")
		)
		(fp_line
			(start 0.12065 -0.305054)
			(end 0.12065 -0.2794)
			(stroke
				(width 0.1)
				(type default)
			)
			(layer "B.Fab")
		)
		(fp_line
			(start 0.67945 -0.305054)
			(end 0.12065 -0.305054)
			(stroke
				(width 0.1)
				(type default)
			)
			(layer "B.Fab")
		)
		(pad "1" smd circle
			(at 0.40005 0 90)
			(size 0 0)
			(layers "B.Cu" "B.Mask" "B.Paste")
			(net "P3V3_AUX")
		)
		(pad "2" smd circle
			(at -0.40005 0 90)
			(size 0 0)
			(layers "B.Cu" "B.Mask" "B.Paste")
			(net "GND")
		)
	)
	(footprint ""
		(layer "B.Cu")
		(at 162.825176 -258.399534 -90)
		(property "Reference" "C479"
			(at 0 0 90)
			(layer "B.SilkS")
			(hide yes)
			(effects
				(font
					(size 1.27 1.27)
				)
				(justify mirror)
			)
		)
		(property "Value" ""
			(at 0 0 90)
			(layer "B.Fab")
			(effects
				(font
					(size 1.27 1.27)
				)
				(justify mirror)
			)
		)
		(duplicate_pad_numbers_are_jumpers no)
		(fp_line
			(start -1.524 0.762)
			(end 1.524 0.762)
			(stroke
				(width 0.1524)
				(type default)
			)
			(layer "B.SilkS")
		)
		(fp_line
			(start 1.524 0.762)
			(end 1.524 -0.762)
			(stroke
				(width 0.1524)
				(type default)
			)
			(layer "B.SilkS")
		)
		(fp_line
			(start -1.524 -0.762)
			(end -1.524 0.762)
			(stroke
				(width 0.1524)
				(type default)
			)
			(layer "B.SilkS")
		)
		(fp_line
			(start 1.524 -0.762)
			(end -1.524 -0.762)
			(stroke
				(width 0.1524)
				(type default)
			)
			(layer "B.SilkS")
		)
		(fp_line
			(start -1.1049 0.724916)
			(end -1.1049 -0.724916)
			(stroke
				(width 0.1)
				(type default)
			)
			(layer "B.Fab")
		)
		(fp_line
			(start 1.1049 0.724916)
			(end -1.1049 0.724916)
			(stroke
				(width 0.1)
				(type default)
			)
			(layer "B.Fab")
		)
		(fp_line
			(start -1.1049 -0.724916)
			(end 1.1049 -0.724916)
			(stroke
				(width 0.1)
				(type default)
			)
			(layer "B.Fab")
		)
		(fp_line
			(start 1.1049 -0.724916)
			(end 1.1049 0.724916)
			(stroke
				(width 0.1)
				(type default)
			)
			(layer "B.Fab")
		)
		(pad "1" smd rect
			(at 0.889 0 270)
			(size 1.016 1.27)
			(layers "B.Cu" "B.Mask" "B.Paste")
			(net "PVCCFA_EHV_FIVRA_CPU1")
		)
		(pad "2" smd rect
			(at -0.889 0 270)
			(size 1.016 1.27)
			(layers "B.Cu" "B.Mask" "B.Paste")
			(net "GND")
		)
	)
)
